(kicad_pcb
	(version 20260206)
	(generator "pcbnew")
	(generator_version "10.0")
	(general
		(thickness 1.6)
		(legacy_teardrops no)
	)
	(paper "A4")
	(title_block
		(title "04192023_DAF0TMB3IC0_F0TG_MB_C_brd_V02_OCP.brd")
		(comment 1 "Grand Teton / footprints 4805-4810 of 8354")
	)
	(layers
		(0 "F.Cu" signal "TOP")
		(4 "In1.Cu" signal "GND")
		(6 "In2.Cu" signal "IN1")
		(8 "In3.Cu" signal "GND1")
		(10 "In4.Cu" signal "IN2")
		(12 "In5.Cu" signal "GND2")
		(14 "In6.Cu" signal "IN3")
		(16 "In7.Cu" signal "GND3")
		(18 "In8.Cu" signal "VCC")
		(20 "In9.Cu" signal "VCC1")
		(22 "In10.Cu" signal "GND4")
		(24 "In11.Cu" signal "IN4")
		(26 "In12.Cu" signal "GND5")
		(28 "In13.Cu" signal "IN5")
		(30 "In14.Cu" signal "GND6")
		(32 "In15.Cu" signal "IN6")
		(34 "In16.Cu" signal "GND7")
		(2 "B.Cu" signal "BOTTOM")
		(9 "F.Adhes" user "F.Adhesive")
		(11 "B.Adhes" user "B.Adhesive")
		(13 "F.Paste" user "Package Geometry/Pastemask Top")
		(15 "B.Paste" user "Package Geometry/Pastemask Bottom")
		(5 "F.SilkS" user "Ref Des/Silkscreen Top")
		(7 "B.SilkS" user "Ref Des/Silkscreen Bottom")
		(1 "F.Mask" user "Board Geometry/Soldermask Top")
		(3 "B.Mask" user "Board Geometry/Soldermask Bottom")
		(17 "Dwgs.User" user "User.Drawings")
		(19 "Cmts.User" user "User.Comments")
		(21 "Eco1.User" user "User.Eco1")
		(23 "Eco2.User" user "User.Eco2")
		(25 "Edge.Cuts" user "Board Geometry/Outline")
		(27 "Margin" user)
		(31 "F.CrtYd" user "Package Geometry/Place Bound Top")
		(29 "B.CrtYd" user "Package Geometry/Place Bound Bottom")
		(35 "F.Fab" user "Ref Des/Assembly Top")
		(33 "B.Fab" user "Ref Des/Assembly Bottom")
	)
	(footprint ""
		(layer "F.Cu")
		(at 34.665158 -171.52366)
		(property "Reference" "R5010"
			(at 0 0 0)
			(layer "F.SilkS")
			(hide yes)
			(effects
				(font
					(size 1.27 1.27)
				)
			)
		)
		(property "Value" ""
			(at 0 0 0)
			(layer "F.Fab")
			(effects
				(font
					(size 1.27 1.27)
				)
			)
		)
		(duplicate_pad_numbers_are_jumpers no)
		(fp_line
			(start -0.7874 -0.4064)
			(end 0.7874 -0.4064)
			(stroke
				(width 0.1524)
				(type default)
			)
			(layer "F.SilkS")
		)
		(fp_line
			(start -0.7874 0.4064)
			(end -0.7874 -0.4064)
			(stroke
				(width 0.1524)
				(type default)
			)
			(layer "F.SilkS")
		)
		(fp_line
			(start 0.7874 -0.4064)
			(end 0.7874 0.4064)
			(stroke
				(width 0.1524)
				(type default)
			)
			(layer "F.SilkS")
		)
		(fp_line
			(start 0.7874 0.4064)
			(end -0.7874 0.4064)
			(stroke
				(width 0.1524)
				(type default)
			)
			(layer "F.SilkS")
		)
		(fp_line
			(start -0.67945 -0.305054)
			(end -0.12065 -0.305054)
			(stroke
				(width 0.1)
				(type default)
			)
			(layer "F.Fab")
		)
		(fp_line
			(start -0.67945 0.3048)
			(end -0.67945 -0.305054)
			(stroke
				(width 0.1)
				(type default)
			)
			(layer "F.Fab")
		)
		(fp_line
			(start -0.12065 -0.305054)
			(end -0.12065 -0.2794)
			(stroke
				(width 0.1)
				(type default)
			)
			(layer "F.Fab")
		)
		(fp_line
			(start -0.12065 -0.2794)
			(end 0.12065 -0.2794)
			(stroke
				(width 0.1)
				(type default)
			)
			(layer "F.Fab")
		)
		(fp_line
			(start -0.12065 0.2794)
			(end -0.12065 0.3048)
			(stroke
				(width 0.1)
				(type default)
			)
			(layer "F.Fab")
		)
		(fp_line
			(start -0.12065 0.3048)
			(end -0.67945 0.3048)
			(stroke
				(width 0.1)
				(type default)
			)
			(layer "F.Fab")
		)
		(fp_line
			(start 0.120396 0.2794)
			(end -0.12065 0.2794)
			(stroke
				(width 0.1)
				(type default)
			)
			(layer "F.Fab")
		)
		(fp_line
			(start 0.120396 0.3048)
			(end 0.120396 0.2794)
			(stroke
				(width 0.1)
				(type default)
			)
			(layer "F.Fab")
		)
		(fp_line
			(start 0.12065 -0.3048)
			(end 0.67945 -0.3048)
			(stroke
				(width 0.1)
				(type default)
			)
			(layer "F.Fab")
		)
		(fp_line
			(start 0.12065 -0.2794)
			(end 0.12065 -0.3048)
			(stroke
				(width 0.1)
				(type default)
			)
			(layer "F.Fab")
		)
		(fp_line
			(start 0.67945 -0.3048)
			(end 0.67945 0.3048)
			(stroke
				(width 0.1)
				(type default)
			)
			(layer "F.Fab")
		)
		(fp_line
			(start 0.67945 0.3048)
			(end 0.120396 0.3048)
			(stroke
				(width 0.1)
				(type default)
			)
			(layer "F.Fab")
		)
		(pad "1" smd circle
			(at -0.40005 0)
			(size 0 0)
			(layers "F.Cu" "F.Mask" "F.Paste")
			(net "PVDD11_S3_P1")
		)
		(pad "2" smd circle
			(at 0.40005 0)
			(size 0 0)
			(layers "F.Cu" "F.Mask" "F.Paste")
			(net "I3C_SPD_DDRAF_CPU1_LVC1_SCL")
		)
	)
	(footprint ""
		(layer "F.Cu")
		(at 323.637148 -42.176954)
		(property "Reference" "R3683"
			(at 0 0 0)
			(layer "F.SilkS")
			(hide yes)
			(effects
				(font
					(size 1.27 1.27)
				)
			)
		)
		(property "Value" ""
			(at 0 0 0)
			(layer "F.Fab")
			(effects
				(font
					(size 1.27 1.27)
				)
			)
		)
		(duplicate_pad_numbers_are_jumpers no)
		(fp_line
			(start -0.7874 -0.4064)
			(end 0.7874 -0.4064)
			(stroke
				(width 0.1524)
				(type default)
			)
			(layer "F.SilkS")
		)
		(fp_line
			(start -0.7874 0.4064)
			(end -0.7874 -0.4064)
			(stroke
				(width 0.1524)
				(type default)
			)
			(layer "F.SilkS")
		)
		(fp_line
			(start 0.7874 -0.4064)
			(end 0.7874 0.4064)
			(stroke
				(width 0.1524)
				(type default)
			)
			(layer "F.SilkS")
		)
		(fp_line
			(start 0.7874 0.4064)
			(end -0.7874 0.4064)
			(stroke
				(width 0.1524)
				(type default)
			)
			(layer "F.SilkS")
		)
		(fp_line
			(start -0.67945 -0.305054)
			(end -0.12065 -0.305054)
			(stroke
				(width 0.1)
				(type default)
			)
			(layer "F.Fab")
		)
		(fp_line
			(start -0.67945 0.3048)
			(end -0.67945 -0.305054)
			(stroke
				(width 0.1)
				(type default)
			)
			(layer "F.Fab")
		)
		(fp_line
			(start -0.12065 -0.305054)
			(end -0.12065 -0.2794)
			(stroke
				(width 0.1)
				(type default)
			)
			(layer "F.Fab")
		)
		(fp_line
			(start -0.12065 -0.2794)
			(end 0.12065 -0.2794)
			(stroke
				(width 0.1)
				(type default)
			)
			(layer "F.Fab")
		)
		(fp_line
			(start -0.12065 0.2794)
			(end -0.12065 0.3048)
			(stroke
				(width 0.1)
				(type default)
			)
			(layer "F.Fab")
		)
		(fp_line
			(start -0.12065 0.3048)
			(end -0.67945 0.3048)
			(stroke
				(width 0.1)
				(type default)
			)
			(layer "F.Fab")
		)
		(fp_line
			(start 0.120396 0.2794)
			(end -0.12065 0.2794)
			(stroke
				(width 0.1)
				(type default)
			)
			(layer "F.Fab")
		)
		(fp_line
			(start 0.120396 0.3048)
			(end 0.120396 0.2794)
			(stroke
				(width 0.1)
				(type default)
			)
			(layer "F.Fab")
		)
		(fp_line
			(start 0.12065 -0.3048)
			(end 0.67945 -0.3048)
			(stroke
				(width 0.1)
				(type default)
			)
			(layer "F.Fab")
		)
		(fp_line
			(start 0.12065 -0.2794)
			(end 0.12065 -0.3048)
			(stroke
				(width 0.1)
				(type default)
			)
			(layer "F.Fab")
		)
		(fp_line
			(start 0.67945 -0.3048)
			(end 0.67945 0.3048)
			(stroke
				(width 0.1)
				(type default)
			)
			(layer "F.Fab")
		)
		(fp_line
			(start 0.67945 0.3048)
			(end 0.120396 0.3048)
			(stroke
				(width 0.1)
				(type default)
			)
			(layer "F.Fab")
		)
		(pad "1" smd rect
			(at -0.40005 0 180)
			(size 0.4572 0.508)
			(layers "F.Cu" "F.Mask" "F.Paste")
			(net "P3V3_ADC")
		)
		(pad "2" smd rect
			(at 0.40005 0 180)
			(size 0.4572 0.508)
			(layers "F.Cu" "F.Mask" "F.Paste")
			(net "P3V3_ADC_MAM")
		)
	)
	(footprint ""
		(layer "F.Cu")
		(at 116.227098 -261.748016 -90)
		(property "Reference" "C2508"
			(at 0 0 270)
			(layer "F.SilkS")
			(hide yes)
			(effects
				(font
					(size 1.27 1.27)
				)
			)
		)
		(property "Value" ""
			(at 0 0 270)
			(layer "F.Fab")
			(effects
				(font
					(size 1.27 1.27)
				)
			)
		)
		(duplicate_pad_numbers_are_jumpers no)
		(fp_line
			(start -0.7874 0.4064)
			(end -0.7874 -0.4064)
			(stroke
				(width 0.1524)
				(type default)
			)
			(layer "F.SilkS")
		)
		(fp_line
			(start 0.7874 0.4064)
			(end -0.7874 0.4064)
			(stroke
				(width 0.1524)
				(type default)
			)
			(layer "F.SilkS")
		)
		(fp_line
			(start -0.7874 -0.4064)
			(end 0.7874 -0.4064)
			(stroke
				(width 0.1524)
				(type default)
			)
			(layer "F.SilkS")
		)
		(fp_line
			(start 0.7874 -0.4064)
			(end 0.7874 0.4064)
			(stroke
				(width 0.1524)
				(type default)
			)
			(layer "F.SilkS")
		)
		(fp_line
			(start -0.67945 0.3048)
			(end -0.67945 -0.305054)
			(stroke
				(width 0.1)
				(type default)
			)
			(layer "F.Fab")
		)
		(fp_line
			(start -0.12065 0.3048)
			(end -0.67945 0.3048)
			(stroke
				(width 0.1)
				(type default)
			)
			(layer "F.Fab")
		)
		(fp_line
			(start 0.120396 0.3048)
			(end 0.120396 0.2794)
			(stroke
				(width 0.1)
				(type default)
			)
			(layer "F.Fab")
		)
		(fp_line
			(start 0.67945 0.3048)
			(end 0.120396 0.3048)
			(stroke
				(width 0.1)
				(type default)
			)
			(layer "F.Fab")
		)
		(fp_line
			(start -0.12065 0.2794)
			(end -0.12065 0.3048)
			(stroke
				(width 0.1)
				(type default)
			)
			(layer "F.Fab")
		)
		(fp_line
			(start 0.120396 0.2794)
			(end -0.12065 0.2794)
			(stroke
				(width 0.1)
				(type default)
			)
			(layer "F.Fab")
		)
		(fp_line
			(start -0.12065 -0.2794)
			(end 0.12065 -0.2794)
			(stroke
				(width 0.1)
				(type default)
			)
			(layer "F.Fab")
		)
		(fp_line
			(start 0.12065 -0.2794)
			(end 0.12065 -0.3048)
			(stroke
				(width 0.1)
				(type default)
			)
			(layer "F.Fab")
		)
		(fp_line
			(start 0.12065 -0.3048)
			(end 0.67945 -0.3048)
			(stroke
				(width 0.1)
				(type default)
			)
			(layer "F.Fab")
		)
		(fp_line
			(start 0.67945 -0.3048)
			(end 0.67945 0.3048)
			(stroke
				(width 0.1)
				(type default)
			)
			(layer "F.Fab")
		)
		(fp_line
			(start -0.67945 -0.305054)
			(end -0.12065 -0.305054)
			(stroke
				(width 0.1)
				(type default)
			)
			(layer "F.Fab")
		)
		(fp_line
			(start -0.12065 -0.305054)
			(end -0.12065 -0.2794)
			(stroke
				(width 0.1)
				(type default)
			)
			(layer "F.Fab")
		)
		(pad "1" smd circle
			(at -0.40005 0 270)
			(size 0 0)
			(layers "F.Cu" "F.Mask" "F.Paste")
			(net "PVDD11_S3_P1")
		)
		(pad "2" smd circle
			(at 0.40005 0 270)
			(size 0 0)
			(layers "F.Cu" "F.Mask" "F.Paste")
			(net "GND")
		)
	)
	(footprint ""
		(layer "F.Cu")
		(at 150.368762 -119.098822)
		(property "Reference" "R2221"
			(at 0 0 0)
			(layer "F.SilkS")
			(hide yes)
			(effects
				(font
					(size 1.27 1.27)
				)
			)
		)
		(property "Value" ""
			(at 0 0 0)
			(layer "F.Fab")
			(effects
				(font
					(size 1.27 1.27)
				)
			)
		)
		(duplicate_pad_numbers_are_jumpers no)
		(fp_line
			(start -0.7874 -0.4064)
			(end 0.7874 -0.4064)
			(stroke
				(width 0.1524)
				(type default)
			)
			(layer "F.SilkS")
		)
		(fp_line
			(start -0.7874 0.4064)
			(end -0.7874 -0.4064)
			(stroke
				(width 0.1524)
				(type default)
			)
			(layer "F.SilkS")
		)
		(fp_line
			(start 0.7874 -0.4064)
			(end 0.7874 0.4064)
			(stroke
				(width 0.1524)
				(type default)
			)
			(layer "F.SilkS")
		)
		(fp_line
			(start 0.7874 0.4064)
			(end -0.7874 0.4064)
			(stroke
				(width 0.1524)
				(type default)
			)
			(layer "F.SilkS")
		)
		(fp_line
			(start -0.67945 -0.305054)
			(end -0.12065 -0.305054)
			(stroke
				(width 0.1)
				(type default)
			)
			(layer "F.Fab")
		)
		(fp_line
			(start -0.67945 0.3048)
			(end -0.67945 -0.305054)
			(stroke
				(width 0.1)
				(type default)
			)
			(layer "F.Fab")
		)
		(fp_line
			(start -0.12065 -0.305054)
			(end -0.12065 -0.2794)
			(stroke
				(width 0.1)
				(type default)
			)
			(layer "F.Fab")
		)
		(fp_line
			(start -0.12065 -0.2794)
			(end 0.12065 -0.2794)
			(stroke
				(width 0.1)
				(type default)
			)
			(layer "F.Fab")
		)
		(fp_line
			(start -0.12065 0.2794)
			(end -0.12065 0.3048)
			(stroke
				(width 0.1)
				(type default)
			)
			(layer "F.Fab")
		)
		(fp_line
			(start -0.12065 0.3048)
			(end -0.67945 0.3048)
			(stroke
				(width 0.1)
				(type default)
			)
			(layer "F.Fab")
		)
		(fp_line
			(start 0.120396 0.2794)
			(end -0.12065 0.2794)
			(stroke
				(width 0.1)
				(type default)
			)
			(layer "F.Fab")
		)
		(fp_line
			(start 0.120396 0.3048)
			(end 0.120396 0.2794)
			(stroke
				(width 0.1)
				(type default)
			)
			(layer "F.Fab")
		)
		(fp_line
			(start 0.12065 -0.3048)
			(end 0.67945 -0.3048)
			(stroke
				(width 0.1)
				(type default)
			)
			(layer "F.Fab")
		)
		(fp_line
			(start 0.12065 -0.2794)
			(end 0.12065 -0.3048)
			(stroke
				(width 0.1)
				(type default)
			)
			(layer "F.Fab")
		)
		(fp_line
			(start 0.67945 -0.3048)
			(end 0.67945 0.3048)
			(stroke
				(width 0.1)
				(type default)
			)
			(layer "F.Fab")
		)
		(fp_line
			(start 0.67945 0.3048)
			(end 0.120396 0.3048)
			(stroke
				(width 0.1)
				(type default)
			)
			(layer "F.Fab")
		)
		(pad "1" smd circle
			(at -0.40005 0)
			(size 0 0)
			(layers "F.Cu" "F.Mask" "F.Paste")
			(net "P12V_AUX")
		)
		(pad "2" smd circle
			(at 0.40005 0)
			(size 0 0)
			(layers "F.Cu" "F.Mask" "F.Paste")
			(net "A_P12V_STBY_FP_TRIGGER")
		)
	)
	(footprint ""
		(layer "F.Cu")
		(at 439.295032 -24.009858)
		(property "Reference" "PR3843"
			(at 0 0 0)
			(layer "F.SilkS")
			(hide yes)
			(effects
				(font
					(size 1.27 1.27)
				)
			)
		)
		(property "Value" ""
			(at 0 0 0)
			(layer "F.Fab")
			(effects
				(font
					(size 1.27 1.27)
				)
			)
		)
		(duplicate_pad_numbers_are_jumpers no)
		(fp_line
			(start -1.2954 -0.5842)
			(end 1.2954 -0.5842)
			(stroke
				(width 0.1524)
				(type default)
			)
			(layer "F.SilkS")
		)
		(fp_line
			(start -1.2954 0.5842)
			(end -1.2954 -0.5842)
			(stroke
				(width 0.1524)
				(type default)
			)
			(layer "F.SilkS")
		)
		(fp_line
			(start 1.2954 -0.5842)
			(end 1.2954 0.5842)
			(stroke
				(width 0.1524)
				(type default)
			)
			(layer "F.SilkS")
		)
		(fp_line
			(start 1.2954 0.5842)
			(end -1.2954 0.5842)
			(stroke
				(width 0.1524)
				(type default)
			)
			(layer "F.SilkS")
		)
		(fp_line
			(start -1.1938 -0.406654)
			(end -0.8636 -0.406654)
			(stroke
				(width 0.1)
				(type default)
			)
			(layer "F.Fab")
		)
		(fp_line
			(start -1.1938 0.4064)
			(end -1.1938 -0.406654)
			(stroke
				(width 0.1)
				(type default)
			)
			(layer "F.Fab")
		)
		(fp_line
			(start -0.8636 -0.4572)
			(end 0.8636 -0.4572)
			(stroke
				(width 0.1)
				(type default)
			)
			(layer "F.Fab")
		)
		(fp_line
			(start -0.8636 -0.406654)
			(end -0.8636 -0.4572)
			(stroke
				(width 0.1)
				(type default)
			)
			(layer "F.Fab")
		)
		(fp_line
			(start -0.8636 0.4064)
			(end -1.1938 0.4064)
			(stroke
				(width 0.1)
				(type default)
			)
			(layer "F.Fab")
		)
		(fp_line
			(start -0.8636 0.4318)
			(end -0.8636 0.4064)
			(stroke
				(width 0.1)
				(type default)
			)
			(layer "F.Fab")
		)
		(fp_line
			(start -0.8636 0.4572)
			(end -0.8636 0.4318)
			(stroke
				(width 0.1)
				(type default)
			)
			(layer "F.Fab")
		)
		(fp_line
			(start 0.8636 -0.4572)
			(end 0.8636 -0.406654)
			(stroke
				(width 0.1)
				(type default)
			)
			(layer "F.Fab")
		)
		(fp_line
			(start 0.8636 -0.406654)
			(end 1.1938 -0.406654)
			(stroke
				(width 0.1)
				(type default)
			)
			(layer "F.Fab")
		)
		(fp_line
			(start 0.8636 0.4064)
			(end 0.8636 0.4572)
			(stroke
				(width 0.1)
				(type default)
			)
			(layer "F.Fab")
		)
		(fp_line
			(start 0.8636 0.4572)
			(end -0.8636 0.4572)
			(stroke
				(width 0.1)
				(type default)
			)
			(layer "F.Fab")
		)
		(fp_line
			(start 1.1938 -0.406654)
			(end 1.1938 0.4064)
			(stroke
				(width 0.1)
				(type default)
			)
			(layer "F.Fab")
		)
		(fp_line
			(start 1.1938 0.4064)
			(end 0.8636 0.4064)
			(stroke
				(width 0.1)
				(type default)
			)
			(layer "F.Fab")
		)
		(pad "1" smd rect
			(at -0.7366 0 270)
			(size 0.7112 0.8128)
			(layers "F.Cu" "F.Mask" "F.Paste")
			(net "P12V_AUX")
		)
		(pad "2" smd rect
			(at 0.7366 0 270)
			(size 0.7112 0.8128)
			(layers "F.Cu" "F.Mask" "F.Paste")
			(net "P12V_OCP_AVIN_PD_1")
		)
	)
	(footprint ""
		(layer "F.Cu")
		(at 63.25616 -56.98998)
		(property "Reference" "R1525"
			(at 0 0 0)
			(layer "F.SilkS")
			(hide yes)
			(effects
				(font
					(size 1.27 1.27)
				)
			)
		)
		(property "Value" ""
			(at 0 0 0)
			(layer "F.Fab")
			(effects
				(font
					(size 1.27 1.27)
				)
			)
		)
		(duplicate_pad_numbers_are_jumpers no)
		(fp_line
			(start -0.7874 -0.4064)
			(end 0.7874 -0.4064)
			(stroke
				(width 0.1524)
				(type default)
			)
			(layer "F.SilkS")
		)
		(fp_line
			(start -0.7874 0.4064)
			(end -0.7874 -0.4064)
			(stroke
				(width 0.1524)
				(type default)
			)
			(layer "F.SilkS")
		)
		(fp_line
			(start 0.7874 -0.4064)
			(end 0.7874 0.4064)
			(stroke
				(width 0.1524)
				(type default)
			)
			(layer "F.SilkS")
		)
		(fp_line
			(start 0.7874 0.4064)
			(end -0.7874 0.4064)
			(stroke
				(width 0.1524)
				(type default)
			)
			(layer "F.SilkS")
		)
		(fp_line
			(start -0.67945 -0.305054)
			(end -0.12065 -0.305054)
			(stroke
				(width 0.1)
				(type default)
			)
			(layer "F.Fab")
		)
		(fp_line
			(start -0.67945 0.3048)
			(end -0.67945 -0.305054)
			(stroke
				(width 0.1)
				(type default)
			)
			(layer "F.Fab")
		)
		(fp_line
			(start -0.12065 -0.305054)
			(end -0.12065 -0.2794)
			(stroke
				(width 0.1)
				(type default)
			)
			(layer "F.Fab")
		)
		(fp_line
			(start -0.12065 -0.2794)
			(end 0.12065 -0.2794)
			(stroke
				(width 0.1)
				(type default)
			)
			(layer "F.Fab")
		)
		(fp_line
			(start -0.12065 0.2794)
			(end -0.12065 0.3048)
			(stroke
				(width 0.1)
				(type default)
			)
			(layer "F.Fab")
		)
		(fp_line
			(start -0.12065 0.3048)
			(end -0.67945 0.3048)
			(stroke
				(width 0.1)
				(type default)
			)
			(layer "F.Fab")
		)
		(fp_line
			(start 0.120396 0.2794)
			(end -0.12065 0.2794)
			(stroke
				(width 0.1)
				(type default)
			)
			(layer "F.Fab")
		)
		(fp_line
			(start 0.120396 0.3048)
			(end 0.120396 0.2794)
			(stroke
				(width 0.1)
				(type default)
			)
			(layer "F.Fab")
		)
		(fp_line
			(start 0.12065 -0.3048)
			(end 0.67945 -0.3048)
			(stroke
				(width 0.1)
				(type default)
			)
			(layer "F.Fab")
		)
		(fp_line
			(start 0.12065 -0.2794)
			(end 0.12065 -0.3048)
			(stroke
				(width 0.1)
				(type default)
			)
			(layer "F.Fab")
		)
		(fp_line
			(start 0.67945 -0.3048)
			(end 0.67945 0.3048)
			(stroke
				(width 0.1)
				(type default)
			)
			(layer "F.Fab")
		)
		(fp_line
			(start 0.67945 0.3048)
			(end 0.120396 0.3048)
			(stroke
				(width 0.1)
				(type default)
			)
			(layer "F.Fab")
		)
		(pad "1" smd circle
			(at -0.40005 0)
			(size 0 0)
			(layers "F.Cu" "F.Mask" "F.Paste")
			(net "OCP_V3_2_P3V3_PWRGD")
		)
		(pad "2" smd circle
			(at 0.40005 0)
			(size 0 0)
			(layers "F.Cu" "F.Mask" "F.Paste")
			(net "OCP_V3_2_P3V3_R3_PWRGD")
		)
	)
)
